# T6G (Grand Teton) — schematic netlist excerpt (pin names and nets, part order shuffled) for the footprints in the layout excerpt that follows; sources: Cadence DE-HDL packaged netlist, KiCad conversion of 04192023_DAF0TMB3IC0_F0TG_MB_C_brd_V02_OCP.brd

R569  Q_RES  1K 1% CHIP  pkg 0402LF  page 188 : A = SW_P3V3_EN_ISO_R ; B = SW_P3V3_EN_ISO
C2273  Q_CAP  22UF 4V 20% X6S  pkg C0402  page 72 : A = PVDDCR_SOC_P1 ; B = GND
R970  Q_RES  10K 1% CHIP  pkg 0201LF  page 276 : A = RST_RT_CPU0_P0_PERST_R_N ; B = GND

(kicad_pcb
	(version 20260206)
	(generator "pcbnew")
	(generator_version "10.0")
	(general
		(thickness 1.6)
		(legacy_teardrops no)
	)
	(paper "A4")
	(title_block
		(title "04192023_DAF0TMB3IC0_F0TG_MB_C_brd_V02_OCP.brd")
		(comment 1 "Grand Teton / footprints 1601-1603 of 8354")
	)
	(layers
		(0 "F.Cu" signal "TOP")
		(4 "In1.Cu" signal "GND")
		(6 "In2.Cu" signal "IN1")
		(8 "In3.Cu" signal "GND1")
		(10 "In4.Cu" signal "IN2")
		(12 "In5.Cu" signal "GND2")
		(14 "In6.Cu" signal "IN3")
		(16 "In7.Cu" signal "GND3")
		(18 "In8.Cu" signal "VCC")
		(20 "In9.Cu" signal "VCC1")
		(22 "In10.Cu" signal "GND4")
		(24 "In11.Cu" signal "IN4")
		(26 "In12.Cu" signal "GND5")
		(28 "In13.Cu" signal "IN5")
		(30 "In14.Cu" signal "GND6")
		(32 "In15.Cu" signal "IN6")
		(34 "In16.Cu" signal "GND7")
		(2 "B.Cu" signal "BOTTOM")
		(9 "F.Adhes" user "F.Adhesive")
		(11 "B.Adhes" user "B.Adhesive")
		(13 "F.Paste" user "Package Geometry/Pastemask Top")
		(15 "B.Paste" user "Package Geometry/Pastemask Bottom")
		(5 "F.SilkS" user "Ref Des/Silkscreen Top")
		(7 "B.SilkS" user "Ref Des/Silkscreen Bottom")
		(1 "F.Mask" user "Board Geometry/Soldermask Top")
		(3 "B.Mask" user "Board Geometry/Soldermask Bottom")
		(17 "Dwgs.User" user "User.Drawings")
		(19 "Cmts.User" user "User.Comments")
		(21 "Eco1.User" user "User.Eco1")
		(23 "Eco2.User" user "User.Eco2")
		(25 "Edge.Cuts" user "Board Geometry/Outline")
		(27 "Margin" user)
		(31 "F.CrtYd" user "Package Geometry/Place Bound Top")
		(29 "B.CrtYd" user "Package Geometry/Place Bound Bottom")
		(35 "F.Fab" user "Ref Des/Assembly Top")
		(33 "B.Fab" user "Ref Des/Assembly Bottom")
	)
	(footprint ""
		(layer "F.Cu")
		(at 117.895624 -261.255256 180)
		(property "Reference" "C2273"
			(at 0 0 180)
			(layer "F.SilkS")
			(hide yes)
			(effects
				(font
					(size 1.27 1.27)
				)
			)
		)
		(property "Value" ""
			(at 0 0 180)
			(layer "F.Fab")
			(effects
				(font
					(size 1.27 1.27)
				)
			)
		)
		(duplicate_pad_numbers_are_jumpers no)
		(fp_line
			(start 0.7874 0.4064)
			(end -0.7874 0.4064)
			(stroke
				(width 0.1524)
				(type default)
			)
			(layer "F.SilkS")
		)
		(fp_line
			(start 0.7874 -0.4064)
			(end 0.7874 0.4064)
			(stroke
				(width 0.1524)
				(type default)
			)
			(layer "F.SilkS")
		)
		(fp_line
			(start -0.7874 0.4064)
			(end -0.7874 -0.4064)
			(stroke
				(width 0.1524)
				(type default)
			)
			(layer "F.SilkS")
		)
		(fp_line
			(start -0.7874 -0.4064)
			(end 0.7874 -0.4064)
			(stroke
				(width 0.1524)
				(type default)
			)
			(layer "F.SilkS")
		)
		(fp_line
			(start 0.67945 0.3048)
			(end 0.120396 0.3048)
			(stroke
				(width 0.1)
				(type default)
			)
			(layer "F.Fab")
		)
		(fp_line
			(start 0.67945 -0.3048)
			(end 0.67945 0.3048)
			(stroke
				(width 0.1)
				(type default)
			)
			(layer "F.Fab")
		)
		(fp_line
			(start 0.12065 -0.2794)
			(end 0.12065 -0.3048)
			(stroke
				(width 0.1)
				(type default)
			)
			(layer "F.Fab")
		)
		(fp_line
			(start 0.12065 -0.3048)
			(end 0.67945 -0.3048)
			(stroke
				(width 0.1)
				(type default)
			)
			(layer "F.Fab")
		)
		(fp_line
			(start 0.120396 0.3048)
			(end 0.120396 0.2794)
			(stroke
				(width 0.1)
				(type default)
			)
			(layer "F.Fab")
		)
		(fp_line
			(start 0.120396 0.2794)
			(end -0.12065 0.2794)
			(stroke
				(width 0.1)
				(type default)
			)
			(layer "F.Fab")
		)
		(fp_line
			(start -0.12065 0.3048)
			(end -0.67945 0.3048)
			(stroke
				(width 0.1)
				(type default)
			)
			(layer "F.Fab")
		)
		(fp_line
			(start -0.12065 0.2794)
			(end -0.12065 0.3048)
			(stroke
				(width 0.1)
				(type default)
			)
			(layer "F.Fab")
		)
		(fp_line
			(start -0.12065 -0.2794)
			(end 0.12065 -0.2794)
			(stroke
				(width 0.1)
				(type default)
			)
			(layer "F.Fab")
		)
		(fp_line
			(start -0.12065 -0.305054)
			(end -0.12065 -0.2794)
			(stroke
				(width 0.1)
				(type default)
			)
			(layer "F.Fab")
		)
		(fp_line
			(start -0.67945 0.3048)
			(end -0.67945 -0.305054)
			(stroke
				(width 0.1)
				(type default)
			)
			(layer "F.Fab")
		)
		(fp_line
			(start -0.67945 -0.305054)
			(end -0.12065 -0.305054)
			(stroke
				(width 0.1)
				(type default)
			)
			(layer "F.Fab")
		)
		(pad "1" smd circle
			(at -0.40005 0 180)
			(size 0 0)
			(layers "F.Cu" "F.Mask" "F.Paste")
			(net "PVDDCR_SOC_P1")
		)
		(pad "2" smd circle
			(at 0.40005 0 180)
			(size 0 0)
			(layers "F.Cu" "F.Mask" "F.Paste")
			(net "GND")
		)
	)
	(footprint ""
		(layer "F.Cu")
		(at 208.407 -129.54 90)
		(property "Reference" "R569"
			(at 0 0 90)
			(layer "F.SilkS")
			(hide yes)
			(effects
				(font
					(size 1.27 1.27)
				)
			)
		)
		(property "Value" ""
			(at 0 0 90)
			(layer "F.Fab")
			(effects
				(font
					(size 1.27 1.27)
				)
			)
		)
		(duplicate_pad_numbers_are_jumpers no)
		(fp_line
			(start 0.7874 -0.4064)
			(end 0.7874 0.4064)
			(stroke
				(width 0.1524)
				(type default)
			)
			(layer "F.SilkS")
		)
		(fp_line
			(start -0.7874 -0.4064)
			(end 0.7874 -0.4064)
			(stroke
				(width 0.1524)
				(type default)
			)
			(layer "F.SilkS")
		)
		(fp_line
			(start 0.7874 0.4064)
			(end -0.7874 0.4064)
			(stroke
				(width 0.1524)
				(type default)
			)
			(layer "F.SilkS")
		)
		(fp_line
			(start -0.7874 0.4064)
			(end -0.7874 -0.4064)
			(stroke
				(width 0.1524)
				(type default)
			)
			(layer "F.SilkS")
		)
		(fp_line
			(start -0.12065 -0.305054)
			(end -0.12065 -0.2794)
			(stroke
				(width 0.1)
				(type default)
			)
			(layer "F.Fab")
		)
		(fp_line
			(start -0.67945 -0.305054)
			(end -0.12065 -0.305054)
			(stroke
				(width 0.1)
				(type default)
			)
			(layer "F.Fab")
		)
		(fp_line
			(start 0.67945 -0.3048)
			(end 0.67945 0.3048)
			(stroke
				(width 0.1)
				(type default)
			)
			(layer "F.Fab")
		)
		(fp_line
			(start 0.12065 -0.3048)
			(end 0.67945 -0.3048)
			(stroke
				(width 0.1)
				(type default)
			)
			(layer "F.Fab")
		)
		(fp_line
			(start 0.12065 -0.2794)
			(end 0.12065 -0.3048)
			(stroke
				(width 0.1)
				(type default)
			)
			(layer "F.Fab")
		)
		(fp_line
			(start -0.12065 -0.2794)
			(end 0.12065 -0.2794)
			(stroke
				(width 0.1)
				(type default)
			)
			(layer "F.Fab")
		)
		(fp_line
			(start 0.120396 0.2794)
			(end -0.12065 0.2794)
			(stroke
				(width 0.1)
				(type default)
			)
			(layer "F.Fab")
		)
		(fp_line
			(start -0.12065 0.2794)
			(end -0.12065 0.3048)
			(stroke
				(width 0.1)
				(type default)
			)
			(layer "F.Fab")
		)
		(fp_line
			(start 0.67945 0.3048)
			(end 0.120396 0.3048)
			(stroke
				(width 0.1)
				(type default)
			)
			(layer "F.Fab")
		)
		(fp_line
			(start 0.120396 0.3048)
			(end 0.120396 0.2794)
			(stroke
				(width 0.1)
				(type default)
			)
			(layer "F.Fab")
		)
		(fp_line
			(start -0.12065 0.3048)
			(end -0.67945 0.3048)
			(stroke
				(width 0.1)
				(type default)
			)
			(layer "F.Fab")
		)
		(fp_line
			(start -0.67945 0.3048)
			(end -0.67945 -0.305054)
			(stroke
				(width 0.1)
				(type default)
			)
			(layer "F.Fab")
		)
		(pad "1" smd circle
			(at -0.40005 0 90)
			(size 0 0)
			(layers "F.Cu" "F.Mask" "F.Paste")
			(net "SW_P3V3_EN_ISO_R")
		)
		(pad "2" smd circle
			(at 0.40005 0 90)
			(size 0 0)
			(layers "F.Cu" "F.Mask" "F.Paste")
			(net "SW_P3V3_EN_ISO")
		)
	)
	(footprint ""
		(layer "F.Cu")
		(at 324.168262 -402.7424 -90)
		(property "Reference" "R970"
			(at 0 0 270)
			(layer "F.SilkS")
			(hide yes)
			(effects
				(font
					(size 1.27 1.27)
				)
			)
		)
		(property "Value" ""
			(at 0 0 270)
			(layer "F.Fab")
			(effects
				(font
					(size 1.27 1.27)
				)
			)
		)
		(duplicate_pad_numbers_are_jumpers no)
		(fp_line
			(start -0.32512 0.175006)
			(end -0.32512 -0.175006)
			(stroke
				(width 0.1)
				(type default)
			)
			(layer "F.Fab")
		)
		(fp_line
			(start 0.32512 0.175006)
			(end -0.32512 0.175006)
			(stroke
				(width 0.1)
				(type default)
			)
			(layer "F.Fab")
		)
		(fp_line
			(start -0.32512 -0.175006)
			(end 0.32512 -0.175006)
			(stroke
				(width 0.1)
				(type default)
			)
			(layer "F.Fab")
		)
		(fp_line
			(start 0.32512 -0.175006)
			(end 0.32512 0.175006)
			(stroke
				(width 0.1)
				(type default)
			)
			(layer "F.Fab")
		)
		(pad "1" smd rect
			(at -0.2667 0 270)
			(size 0.3048 0.381)
			(layers "F.Cu" "F.Mask" "F.Paste")
			(net "RST_RT_CPU0_P0_PERST_R_N")
		)
		(pad "2" smd rect
			(at 0.2667 0 90)
			(size 0.3048 0.381)
			(layers "F.Cu" "F.Mask" "F.Paste")
			(net "GND")
		)
	)
)
